# S9S_MB_2U (Grand Teton) — schematic netlist excerpt (pin names and nets, part order shuffled) for the footprints in the layout excerpt that follows; sources: Cadence DE-HDL packaged netlist, KiCad conversion of 03242023_DA0F0TMBIJ0_F0T_Motherboard_J_brd_V01_OCP.brd

C57  Q_CAP  10UF 16V 10% X6S  pkg C0805  page 100 : A = P12V_S3_AUX_CPU1_NVDIMM ; B = GND
R760  Q_RES  499 1% CHIP  pkg 0402LF  page 132 : A = PVNN_TERM_CPU0 ; B = DBP_CPU_HOOK8_MBP2_GTL_QS_N
R13  Q_RES  0 5% CHIP  pkg 0402LF  page 14 : A = SVID_CLK0_CPU0 ; B = SVID_CLK0_CPU0_R

(kicad_pcb
	(version 20260206)
	(generator "pcbnew")
	(generator_version "10.0")
	(general
		(thickness 1.6)
		(legacy_teardrops no)
	)
	(paper "A4")
	(title_block
		(title "03242023_DA0F0TMBIJ0_F0T_Motherboard_J_brd_V01_OCP.brd")
		(comment 1 "Grand Teton / footprints 4617-4619 of 6105")
	)
	(layers
		(0 "F.Cu" signal "TOP")
		(4 "In1.Cu" signal "GND")
		(6 "In2.Cu" signal "IN1")
		(8 "In3.Cu" signal "GND1")
		(10 "In4.Cu" signal "IN2")
		(12 "In5.Cu" signal "GND2")
		(14 "In6.Cu" signal "IN3")
		(16 "In7.Cu" signal "GND3")
		(18 "In8.Cu" signal "VCC")
		(20 "In9.Cu" signal "VCC1")
		(22 "In10.Cu" signal "GND4")
		(24 "In11.Cu" signal "IN4")
		(26 "In12.Cu" signal "GND5")
		(28 "In13.Cu" signal "IN5")
		(30 "In14.Cu" signal "GND6")
		(32 "In15.Cu" signal "IN6")
		(34 "In16.Cu" signal "GND7")
		(2 "B.Cu" signal "BOTTOM")
		(9 "F.Adhes" user "F.Adhesive")
		(11 "B.Adhes" user "B.Adhesive")
		(13 "F.Paste" user "Package Geometry/Pastemask Top")
		(15 "B.Paste" user "Package Geometry/Pastemask Bottom")
		(5 "F.SilkS" user "Ref Des/Silkscreen Top")
		(7 "B.SilkS" user "Ref Des/Silkscreen Bottom")
		(1 "F.Mask" user "Board Geometry/Soldermask Top")
		(3 "B.Mask" user "Board Geometry/Soldermask Bottom")
		(17 "Dwgs.User" user "User.Drawings")
		(19 "Cmts.User" user "User.Comments")
		(21 "Eco1.User" user "User.Eco1")
		(23 "Eco2.User" user "User.Eco2")
		(25 "Edge.Cuts" user "Board Geometry/Outline")
		(27 "Margin" user)
		(31 "F.CrtYd" user "Package Geometry/Place Bound Top")
		(29 "B.CrtYd" user "Package Geometry/Place Bound Bottom")
		(35 "F.Fab" user "Ref Des/Assembly Top")
		(33 "B.Fab" user "Ref Des/Assembly Bottom")
	)
	(footprint ""
		(layer "B.Cu")
		(at 305.942238 -194.72021 90)
		(property "Reference" "R13"
			(at 0 0 90)
			(layer "B.SilkS")
			(hide yes)
			(effects
				(font
					(size 1.27 1.27)
				)
				(justify mirror)
			)
		)
		(property "Value" ""
			(at 0 0 90)
			(layer "B.Fab")
			(effects
				(font
					(size 1.27 1.27)
				)
				(justify mirror)
			)
		)
		(duplicate_pad_numbers_are_jumpers no)
		(fp_line
			(start 0.7874 -0.4064)
			(end -0.7874 -0.4064)
			(stroke
				(width 0.1524)
				(type default)
			)
			(layer "B.SilkS")
		)
		(fp_line
			(start -0.7874 -0.4064)
			(end -0.7874 0.4064)
			(stroke
				(width 0.1524)
				(type default)
			)
			(layer "B.SilkS")
		)
		(fp_line
			(start 0.7874 0.4064)
			(end 0.7874 -0.4064)
			(stroke
				(width 0.1524)
				(type default)
			)
			(layer "B.SilkS")
		)
		(fp_line
			(start -0.7874 0.4064)
			(end 0.7874 0.4064)
			(stroke
				(width 0.1524)
				(type default)
			)
			(layer "B.SilkS")
		)
		(fp_line
			(start 0.67945 -0.305054)
			(end 0.12065 -0.305054)
			(stroke
				(width 0.1)
				(type default)
			)
			(layer "B.Fab")
		)
		(fp_line
			(start 0.12065 -0.305054)
			(end 0.12065 -0.2794)
			(stroke
				(width 0.1)
				(type default)
			)
			(layer "B.Fab")
		)
		(fp_line
			(start -0.12065 -0.3048)
			(end -0.67945 -0.3048)
			(stroke
				(width 0.1)
				(type default)
			)
			(layer "B.Fab")
		)
		(fp_line
			(start -0.67945 -0.3048)
			(end -0.67945 0.3048)
			(stroke
				(width 0.1)
				(type default)
			)
			(layer "B.Fab")
		)
		(fp_line
			(start 0.12065 -0.2794)
			(end -0.12065 -0.2794)
			(stroke
				(width 0.1)
				(type default)
			)
			(layer "B.Fab")
		)
		(fp_line
			(start -0.12065 -0.2794)
			(end -0.12065 -0.3048)
			(stroke
				(width 0.1)
				(type default)
			)
			(layer "B.Fab")
		)
		(fp_line
			(start 0.12065 0.2794)
			(end 0.12065 0.3048)
			(stroke
				(width 0.1)
				(type default)
			)
			(layer "B.Fab")
		)
		(fp_line
			(start -0.120396 0.2794)
			(end 0.12065 0.2794)
			(stroke
				(width 0.1)
				(type default)
			)
			(layer "B.Fab")
		)
		(fp_line
			(start 0.67945 0.3048)
			(end 0.67945 -0.305054)
			(stroke
				(width 0.1)
				(type default)
			)
			(layer "B.Fab")
		)
		(fp_line
			(start 0.12065 0.3048)
			(end 0.67945 0.3048)
			(stroke
				(width 0.1)
				(type default)
			)
			(layer "B.Fab")
		)
		(fp_line
			(start -0.120396 0.3048)
			(end -0.120396 0.2794)
			(stroke
				(width 0.1)
				(type default)
			)
			(layer "B.Fab")
		)
		(fp_line
			(start -0.67945 0.3048)
			(end -0.120396 0.3048)
			(stroke
				(width 0.1)
				(type default)
			)
			(layer "B.Fab")
		)
		(pad "1" smd circle
			(at 0.40005 0 270)
			(size 0 0)
			(layers "B.Cu" "B.Mask" "B.Paste")
			(net "SVID_CLK0_CPU0")
		)
		(pad "2" smd circle
			(at -0.40005 0 270)
			(size 0 0)
			(layers "B.Cu" "B.Mask" "B.Paste")
			(net "SVID_CLK0_CPU0_R")
		)
	)
	(footprint ""
		(layer "B.Cu")
		(at 69.353684 -183.303926 90)
		(property "Reference" "R760"
			(at 0 0 90)
			(layer "B.SilkS")
			(hide yes)
			(effects
				(font
					(size 1.27 1.27)
				)
				(justify mirror)
			)
		)
		(property "Value" ""
			(at 0 0 90)
			(layer "B.Fab")
			(effects
				(font
					(size 1.27 1.27)
				)
				(justify mirror)
			)
		)
		(duplicate_pad_numbers_are_jumpers no)
		(fp_line
			(start 0.7874 -0.4064)
			(end -0.7874 -0.4064)
			(stroke
				(width 0.1524)
				(type default)
			)
			(layer "B.SilkS")
		)
		(fp_line
			(start -0.7874 -0.4064)
			(end -0.7874 0.4064)
			(stroke
				(width 0.1524)
				(type default)
			)
			(layer "B.SilkS")
		)
		(fp_line
			(start 0.7874 0.4064)
			(end 0.7874 -0.4064)
			(stroke
				(width 0.1524)
				(type default)
			)
			(layer "B.SilkS")
		)
		(fp_line
			(start -0.7874 0.4064)
			(end 0.7874 0.4064)
			(stroke
				(width 0.1524)
				(type default)
			)
			(layer "B.SilkS")
		)
		(fp_line
			(start 0.67945 -0.305054)
			(end 0.12065 -0.305054)
			(stroke
				(width 0.1)
				(type default)
			)
			(layer "B.Fab")
		)
		(fp_line
			(start 0.12065 -0.305054)
			(end 0.12065 -0.2794)
			(stroke
				(width 0.1)
				(type default)
			)
			(layer "B.Fab")
		)
		(fp_line
			(start -0.12065 -0.3048)
			(end -0.67945 -0.3048)
			(stroke
				(width 0.1)
				(type default)
			)
			(layer "B.Fab")
		)
		(fp_line
			(start -0.67945 -0.3048)
			(end -0.67945 0.3048)
			(stroke
				(width 0.1)
				(type default)
			)
			(layer "B.Fab")
		)
		(fp_line
			(start 0.12065 -0.2794)
			(end -0.12065 -0.2794)
			(stroke
				(width 0.1)
				(type default)
			)
			(layer "B.Fab")
		)
		(fp_line
			(start -0.12065 -0.2794)
			(end -0.12065 -0.3048)
			(stroke
				(width 0.1)
				(type default)
			)
			(layer "B.Fab")
		)
		(fp_line
			(start 0.12065 0.2794)
			(end 0.12065 0.3048)
			(stroke
				(width 0.1)
				(type default)
			)
			(layer "B.Fab")
		)
		(fp_line
			(start -0.120396 0.2794)
			(end 0.12065 0.2794)
			(stroke
				(width 0.1)
				(type default)
			)
			(layer "B.Fab")
		)
		(fp_line
			(start 0.67945 0.3048)
			(end 0.67945 -0.305054)
			(stroke
				(width 0.1)
				(type default)
			)
			(layer "B.Fab")
		)
		(fp_line
			(start 0.12065 0.3048)
			(end 0.67945 0.3048)
			(stroke
				(width 0.1)
				(type default)
			)
			(layer "B.Fab")
		)
		(fp_line
			(start -0.120396 0.3048)
			(end -0.120396 0.2794)
			(stroke
				(width 0.1)
				(type default)
			)
			(layer "B.Fab")
		)
		(fp_line
			(start -0.67945 0.3048)
			(end -0.120396 0.3048)
			(stroke
				(width 0.1)
				(type default)
			)
			(layer "B.Fab")
		)
		(pad "1" smd circle
			(at 0.40005 0 270)
			(size 0 0)
			(layers "B.Cu" "B.Mask" "B.Paste")
			(net "PVNN_TERM_CPU0")
		)
		(pad "2" smd circle
			(at -0.40005 0 270)
			(size 0 0)
			(layers "B.Cu" "B.Mask" "B.Paste")
			(net "DBP_CPU_HOOK8_MBP2_GTL_QS_N")
		)
	)
	(footprint ""
		(layer "B.Cu")
		(at 42.392346 -321.554856 -90)
		(property "Reference" "C57"
			(at 0 0 90)
			(layer "B.SilkS")
			(hide yes)
			(effects
				(font
					(size 1.27 1.27)
				)
				(justify mirror)
			)
		)
		(property "Value" ""
			(at 0 0 90)
			(layer "B.Fab")
			(effects
				(font
					(size 1.27 1.27)
				)
				(justify mirror)
			)
		)
		(duplicate_pad_numbers_are_jumpers no)
		(fp_line
			(start -1.524 0.762)
			(end 1.524 0.762)
			(stroke
				(width 0.1524)
				(type default)
			)
			(layer "B.SilkS")
		)
		(fp_line
			(start 1.524 0.762)
			(end 1.524 -0.762)
			(stroke
				(width 0.1524)
				(type default)
			)
			(layer "B.SilkS")
		)
		(fp_line
			(start -1.524 -0.762)
			(end -1.524 0.762)
			(stroke
				(width 0.1524)
				(type default)
			)
			(layer "B.SilkS")
		)
		(fp_line
			(start 1.524 -0.762)
			(end -1.524 -0.762)
			(stroke
				(width 0.1524)
				(type default)
			)
			(layer "B.SilkS")
		)
		(fp_line
			(start -1.1049 0.724916)
			(end -1.1049 -0.724916)
			(stroke
				(width 0.1)
				(type default)
			)
			(layer "B.Fab")
		)
		(fp_line
			(start 1.1049 0.724916)
			(end -1.1049 0.724916)
			(stroke
				(width 0.1)
				(type default)
			)
			(layer "B.Fab")
		)
		(fp_line
			(start -1.1049 -0.724916)
			(end 1.1049 -0.724916)
			(stroke
				(width 0.1)
				(type default)
			)
			(layer "B.Fab")
		)
		(fp_line
			(start 1.1049 -0.724916)
			(end 1.1049 0.724916)
			(stroke
				(width 0.1)
				(type default)
			)
			(layer "B.Fab")
		)
		(pad "1" smd rect
			(at 0.889 0 270)
			(size 1.016 1.27)
			(layers "B.Cu" "B.Mask" "B.Paste")
			(net "P12V_S3_AUX_CPU1_NVDIMM")
		)
		(pad "2" smd rect
			(at -0.889 0 270)
			(size 1.016 1.27)
			(layers "B.Cu" "B.Mask" "B.Paste")
			(net "GND")
		)
	)
)
